(kicad_pcb
	(version 20260206)
	(generator "pcbnew")
	(generator_version "10.0")
	(general
		(thickness 1.6)
		(legacy_teardrops no)
	)
	(paper "A4")
	(title_block
		(title "03242023_DA0F0TMBIJ0_F0T_Motherboard_J_brd_V01_OCP.brd")
		(comment 1 "Grand Teton / footprints 3028-3033 of 6105")
	)
	(layers
		(0 "F.Cu" signal "TOP")
		(4 "In1.Cu" signal "GND")
		(6 "In2.Cu" signal "IN1")
		(8 "In3.Cu" signal "GND1")
		(10 "In4.Cu" signal "IN2")
		(12 "In5.Cu" signal "GND2")
		(14 "In6.Cu" signal "IN3")
		(16 "In7.Cu" signal "GND3")
		(18 "In8.Cu" signal "VCC")
		(20 "In9.Cu" signal "VCC1")
		(22 "In10.Cu" signal "GND4")
		(24 "In11.Cu" signal "IN4")
		(26 "In12.Cu" signal "GND5")
		(28 "In13.Cu" signal "IN5")
		(30 "In14.Cu" signal "GND6")
		(32 "In15.Cu" signal "IN6")
		(34 "In16.Cu" signal "GND7")
		(2 "B.Cu" signal "BOTTOM")
		(9 "F.Adhes" user "F.Adhesive")
		(11 "B.Adhes" user "B.Adhesive")
		(13 "F.Paste" user "Package Geometry/Pastemask Top")
		(15 "B.Paste" user "Package Geometry/Pastemask Bottom")
		(5 "F.SilkS" user "Ref Des/Silkscreen Top")
		(7 "B.SilkS" user "Ref Des/Silkscreen Bottom")
		(1 "F.Mask" user "Board Geometry/Soldermask Top")
		(3 "B.Mask" user "Board Geometry/Soldermask Bottom")
		(17 "Dwgs.User" user "User.Drawings")
		(19 "Cmts.User" user "User.Comments")
		(21 "Eco1.User" user "User.Eco1")
		(23 "Eco2.User" user "User.Eco2")
		(25 "Edge.Cuts" user "Board Geometry/Outline")
		(27 "Margin" user)
		(31 "F.CrtYd" user "Package Geometry/Place Bound Top")
		(29 "B.CrtYd" user "Package Geometry/Place Bound Bottom")
		(35 "F.Fab" user "Ref Des/Assembly Top")
		(33 "B.Fab" user "Ref Des/Assembly Bottom")
	)
	(footprint ""
		(layer "F.Cu")
		(at 366.48263 -240.276888 90)
		(property "Reference" "C415"
			(at 0 0 90)
			(layer "F.SilkS")
			(hide yes)
			(effects
				(font
					(size 1.27 1.27)
				)
			)
		)
		(property "Value" ""
			(at 0 0 90)
			(layer "F.Fab")
			(effects
				(font
					(size 1.27 1.27)
				)
			)
		)
		(duplicate_pad_numbers_are_jumpers no)
		(fp_line
			(start 0.7874 -0.4064)
			(end 0.7874 0.4064)
			(stroke
				(width 0.1524)
				(type default)
			)
			(layer "F.SilkS")
		)
		(fp_line
			(start -0.7874 -0.4064)
			(end 0.7874 -0.4064)
			(stroke
				(width 0.1524)
				(type default)
			)
			(layer "F.SilkS")
		)
		(fp_line
			(start 0.7874 0.4064)
			(end -0.7874 0.4064)
			(stroke
				(width 0.1524)
				(type default)
			)
			(layer "F.SilkS")
		)
		(fp_line
			(start -0.7874 0.4064)
			(end -0.7874 -0.4064)
			(stroke
				(width 0.1524)
				(type default)
			)
			(layer "F.SilkS")
		)
		(fp_line
			(start -0.12065 -0.305054)
			(end -0.12065 -0.2794)
			(stroke
				(width 0.1)
				(type default)
			)
			(layer "F.Fab")
		)
		(fp_line
			(start -0.67945 -0.305054)
			(end -0.12065 -0.305054)
			(stroke
				(width 0.1)
				(type default)
			)
			(layer "F.Fab")
		)
		(fp_line
			(start 0.67945 -0.3048)
			(end 0.67945 0.3048)
			(stroke
				(width 0.1)
				(type default)
			)
			(layer "F.Fab")
		)
		(fp_line
			(start 0.12065 -0.3048)
			(end 0.67945 -0.3048)
			(stroke
				(width 0.1)
				(type default)
			)
			(layer "F.Fab")
		)
		(fp_line
			(start 0.12065 -0.2794)
			(end 0.12065 -0.3048)
			(stroke
				(width 0.1)
				(type default)
			)
			(layer "F.Fab")
		)
		(fp_line
			(start -0.12065 -0.2794)
			(end 0.12065 -0.2794)
			(stroke
				(width 0.1)
				(type default)
			)
			(layer "F.Fab")
		)
		(fp_line
			(start 0.120396 0.2794)
			(end -0.12065 0.2794)
			(stroke
				(width 0.1)
				(type default)
			)
			(layer "F.Fab")
		)
		(fp_line
			(start -0.12065 0.2794)
			(end -0.12065 0.3048)
			(stroke
				(width 0.1)
				(type default)
			)
			(layer "F.Fab")
		)
		(fp_line
			(start 0.67945 0.3048)
			(end 0.120396 0.3048)
			(stroke
				(width 0.1)
				(type default)
			)
			(layer "F.Fab")
		)
		(fp_line
			(start 0.120396 0.3048)
			(end 0.120396 0.2794)
			(stroke
				(width 0.1)
				(type default)
			)
			(layer "F.Fab")
		)
		(fp_line
			(start -0.12065 0.3048)
			(end -0.67945 0.3048)
			(stroke
				(width 0.1)
				(type default)
			)
			(layer "F.Fab")
		)
		(fp_line
			(start -0.67945 0.3048)
			(end -0.67945 -0.305054)
			(stroke
				(width 0.1)
				(type default)
			)
			(layer "F.Fab")
		)
		(pad "1" smd circle
			(at -0.40005 0 90)
			(size 0 0)
			(layers "F.Cu" "F.Mask" "F.Paste")
			(net "PVCCFA_EHV_FIVRA_CPU0")
		)
		(pad "2" smd circle
			(at 0.40005 0 90)
			(size 0 0)
			(layers "F.Cu" "F.Mask" "F.Paste")
			(net "GND")
		)
	)
	(footprint ""
		(layer "F.Cu")
		(at 105.696004 -393.711684 180)
		(property "Reference" "U255"
			(at 1.799844 -3.027426 0)
			(unlocked yes)
			(layer "F.SilkS")
			(effects
				(font
					(size 0.7874 0.5842)
					(thickness 0.1524)
				)
				(justify left)
			)
		)
		(property "Value" ""
			(at 0 0 180)
			(layer "F.Fab")
			(effects
				(font
					(size 1.27 1.27)
				)
			)
		)
		(duplicate_pad_numbers_are_jumpers no)
		(fp_line
			(start 1.38176 1.100074)
			(end 1.38176 -1.100074)
			(stroke
				(width 0.1524)
				(type default)
			)
			(layer "F.SilkS")
		)
		(fp_line
			(start 1.38176 -1.100074)
			(end 0.592074 -1.100074)
			(stroke
				(width 0.1524)
				(type default)
			)
			(layer "F.SilkS")
		)
		(fp_line
			(start 0.456184 1.100074)
			(end 1.38176 1.100074)
			(stroke
				(width 0.1524)
				(type default)
			)
			(layer "F.SilkS")
		)
		(fp_line
			(start -0.592074 -1.100074)
			(end -1.38176 -1.100074)
			(stroke
				(width 0.1524)
				(type default)
			)
			(layer "F.SilkS")
		)
		(fp_line
			(start -1.38176 1.100074)
			(end -0.305816 1.100074)
			(stroke
				(width 0.1524)
				(type default)
			)
			(layer "F.SilkS")
		)
		(fp_line
			(start -1.38176 -1.100074)
			(end -1.38176 1.100074)
			(stroke
				(width 0.1524)
				(type default)
			)
			(layer "F.SilkS")
		)
		(fp_poly
			(pts
				(xy -1.260856 -1.255014) (xy -1.728216 -1.410716) (xy -1.416812 -1.722374)
			)
			(stroke
				(width 0)
				(type default)
			)
			(fill yes)
			(layer "F.SilkS")
		)
		(fp_line
			(start 0.674878 1.100074)
			(end 0.674878 -1.100074)
			(stroke
				(width 0.1)
				(type default)
			)
			(layer "F.Fab")
		)
		(fp_line
			(start 0.674878 -1.100074)
			(end -0.674878 -1.100074)
			(stroke
				(width 0.1)
				(type default)
			)
			(layer "F.Fab")
		)
		(fp_line
			(start -0.674878 1.100074)
			(end 0.674878 1.100074)
			(stroke
				(width 0.1)
				(type default)
			)
			(layer "F.Fab")
		)
		(fp_line
			(start -0.674878 -1.100074)
			(end -0.674878 1.100074)
			(stroke
				(width 0.1)
				(type default)
			)
			(layer "F.Fab")
		)
		(fp_poly
			(pts
				(xy -1.9431 -0.870204) (xy -1.50241 -0.649986) (xy -1.9431 -0.429768)
			)
			(stroke
				(width 0)
				(type default)
			)
			(fill yes)
			(layer "F.Fab")
		)
		(pad "1" smd rect
			(at -0.94996 -0.649986 90)
			(size 0.4318 0.6096)
			(layers "F.Cu" "F.Mask" "F.Paste")
			(net "GPU_NVS_PWR_BRAKE_N")
		)
		(pad "2" smd rect
			(at -0.94996 0 90)
			(size 0.4318 0.6096)
			(layers "F.Cu" "F.Mask" "F.Paste")
			(net "GND")
		)
		(pad "3" smd rect
			(at -0.94996 0.649986 90)
			(size 0.4318 0.6096)
			(layers "F.Cu" "F.Mask" "F.Paste")
			(net "GPU_FPGA_EROT_RST_N")
		)
		(pad "4" smd rect
			(at 0.94996 0.649986 90)
			(size 0.4318 0.6096)
			(layers "F.Cu" "F.Mask" "F.Paste")
			(net "GPU_FPGA_EROT_RST_BUF_R_N")
		)
		(pad "5" smd rect
			(at 0.94996 0 90)
			(size 0.4318 0.6096)
			(layers "F.Cu" "F.Mask" "F.Paste")
			(net "P3V3_AUX")
		)
		(pad "6" smd rect
			(at 0.94996 -0.649986 90)
			(size 0.4318 0.6096)
			(layers "F.Cu" "F.Mask" "F.Paste")
			(net "GPU_NVS_PWR_BRAKE_N_R")
		)
	)
	(footprint ""
		(layer "F.Cu")
		(at 506.259338 -427.45025 180)
		(property "Reference" "DB3"
			(at -2.693924 -0.263398 90)
			(unlocked yes)
			(layer "F.SilkS")
			(effects
				(font
					(size 0.7874 0.5842)
					(thickness 0.1524)
				)
				(justify left)
			)
		)
		(property "Value" ""
			(at 0 0 180)
			(layer "F.Fab")
			(effects
				(font
					(size 1.27 1.27)
				)
			)
		)
		(duplicate_pad_numbers_are_jumpers no)
		(fp_line
			(start 3.330702 -4.771136)
			(end 0 4.011168)
			(stroke
				(width 0.1524)
				(type default)
			)
			(layer "F.SilkS")
		)
		(fp_line
			(start 0 4.011168)
			(end -3.330702 -4.771136)
			(stroke
				(width 0.1524)
				(type default)
			)
			(layer "F.SilkS")
		)
		(fp_line
			(start -3.330702 -4.771136)
			(end 3.330702 -4.771136)
			(stroke
				(width 0.1524)
				(type default)
			)
			(layer "F.SilkS")
		)
		(fp_line
			(start 3.330702 -4.771136)
			(end 0 4.011168)
			(stroke
				(width 0.1)
				(type default)
			)
			(layer "F.Fab")
		)
		(fp_line
			(start 0 4.011168)
			(end -3.330702 -4.771136)
			(stroke
				(width 0.1)
				(type default)
			)
			(layer "F.Fab")
		)
		(fp_line
			(start -3.330702 -4.771136)
			(end 3.330702 -4.771136)
			(stroke
				(width 0.1)
				(type default)
			)
			(layer "F.Fab")
		)
		(pad "1" thru_hole circle
			(at 0 0 180)
			(size 2.159 2.159)
			(drill 1.7018)
			(layers "*.Cu" "*.Mask")
			(remove_unused_layers no)
			(net "T1_GND")
			(clearance 0.0254)
			(thermal_gap 0.0254)
		)
		(pad "2" thru_hole circle
			(at -1.27 -3.348736 180)
			(size 2.159 2.159)
			(drill 1.7018)
			(layers "*.Cu" "*.Mask")
			(remove_unused_layers no)
			(net "TDR_SE_40_OHM_IN2")
			(clearance 0.0254)
			(thermal_gap 0.0254)
		)
		(pad "3" thru_hole circle
			(at 1.27 -3.348736 180)
			(size 2.159 2.159)
			(drill 1.7018)
			(layers "*.Cu" "*.Mask")
			(remove_unused_layers no)
			(net "TDR_SE_40_OHM_IN2")
			(clearance 0.0254)
			(thermal_gap 0.0254)
		)
	)
	(footprint ""
		(layer "F.Cu")
		(at 50.43551 -157.172914 180)
		(property "Reference" "PR1794"
			(at 0 0 180)
			(layer "F.SilkS")
			(hide yes)
			(effects
				(font
					(size 1.27 1.27)
				)
			)
		)
		(property "Value" ""
			(at 0 0 180)
			(layer "F.Fab")
			(effects
				(font
					(size 1.27 1.27)
				)
			)
		)
		(duplicate_pad_numbers_are_jumpers no)
		(fp_line
			(start 0.7874 0.4064)
			(end -0.7874 0.4064)
			(stroke
				(width 0.1524)
				(type default)
			)
			(layer "F.SilkS")
		)
		(fp_line
			(start 0.7874 -0.4064)
			(end 0.7874 0.4064)
			(stroke
				(width 0.1524)
				(type default)
			)
			(layer "F.SilkS")
		)
		(fp_line
			(start -0.7874 0.4064)
			(end -0.7874 -0.4064)
			(stroke
				(width 0.1524)
				(type default)
			)
			(layer "F.SilkS")
		)
		(fp_line
			(start -0.7874 -0.4064)
			(end 0.7874 -0.4064)
			(stroke
				(width 0.1524)
				(type default)
			)
			(layer "F.SilkS")
		)
		(fp_line
			(start 0.67945 0.3048)
			(end 0.120396 0.3048)
			(stroke
				(width 0.1)
				(type default)
			)
			(layer "F.Fab")
		)
		(fp_line
			(start 0.67945 -0.3048)
			(end 0.67945 0.3048)
			(stroke
				(width 0.1)
				(type default)
			)
			(layer "F.Fab")
		)
		(fp_line
			(start 0.12065 -0.2794)
			(end 0.12065 -0.3048)
			(stroke
				(width 0.1)
				(type default)
			)
			(layer "F.Fab")
		)
		(fp_line
			(start 0.12065 -0.3048)
			(end 0.67945 -0.3048)
			(stroke
				(width 0.1)
				(type default)
			)
			(layer "F.Fab")
		)
		(fp_line
			(start 0.120396 0.3048)
			(end 0.120396 0.2794)
			(stroke
				(width 0.1)
				(type default)
			)
			(layer "F.Fab")
		)
		(fp_line
			(start 0.120396 0.2794)
			(end -0.12065 0.2794)
			(stroke
				(width 0.1)
				(type default)
			)
			(layer "F.Fab")
		)
		(fp_line
			(start -0.12065 0.3048)
			(end -0.67945 0.3048)
			(stroke
				(width 0.1)
				(type default)
			)
			(layer "F.Fab")
		)
		(fp_line
			(start -0.12065 0.2794)
			(end -0.12065 0.3048)
			(stroke
				(width 0.1)
				(type default)
			)
			(layer "F.Fab")
		)
		(fp_line
			(start -0.12065 -0.2794)
			(end 0.12065 -0.2794)
			(stroke
				(width 0.1)
				(type default)
			)
			(layer "F.Fab")
		)
		(fp_line
			(start -0.12065 -0.305054)
			(end -0.12065 -0.2794)
			(stroke
				(width 0.1)
				(type default)
			)
			(layer "F.Fab")
		)
		(fp_line
			(start -0.67945 0.3048)
			(end -0.67945 -0.305054)
			(stroke
				(width 0.1)
				(type default)
			)
			(layer "F.Fab")
		)
		(fp_line
			(start -0.67945 -0.305054)
			(end -0.12065 -0.305054)
			(stroke
				(width 0.1)
				(type default)
			)
			(layer "F.Fab")
		)
		(pad "1" smd circle
			(at -0.40005 0 180)
			(size 0 0)
			(layers "F.Cu" "F.Mask" "F.Paste")
			(net "SW_PVCCINFAON_CPU1_BOOT1")
		)
		(pad "2" smd circle
			(at 0.40005 0 180)
			(size 0 0)
			(layers "F.Cu" "F.Mask" "F.Paste")
			(net "SW_PVCCINFAON_CPU1_BOOT1_R")
		)
	)
	(footprint ""
		(layer "F.Cu")
		(at 368.7318 -74.3458 -90)
		(property "Reference" "R4704"
			(at 0 0 270)
			(layer "F.SilkS")
			(hide yes)
			(effects
				(font
					(size 1.27 1.27)
				)
			)
		)
		(property "Value" ""
			(at 0 0 270)
			(layer "F.Fab")
			(effects
				(font
					(size 1.27 1.27)
				)
			)
		)
		(duplicate_pad_numbers_are_jumpers no)
		(fp_line
			(start -0.7874 0.4064)
			(end -0.7874 -0.4064)
			(stroke
				(width 0.1524)
				(type default)
			)
			(layer "F.SilkS")
		)
		(fp_line
			(start 0.7874 0.4064)
			(end -0.7874 0.4064)
			(stroke
				(width 0.1524)
				(type default)
			)
			(layer "F.SilkS")
		)
		(fp_line
			(start -0.7874 -0.4064)
			(end 0.7874 -0.4064)
			(stroke
				(width 0.1524)
				(type default)
			)
			(layer "F.SilkS")
		)
		(fp_line
			(start 0.7874 -0.4064)
			(end 0.7874 0.4064)
			(stroke
				(width 0.1524)
				(type default)
			)
			(layer "F.SilkS")
		)
		(fp_line
			(start -0.67945 0.3048)
			(end -0.67945 -0.305054)
			(stroke
				(width 0.1)
				(type default)
			)
			(layer "F.Fab")
		)
		(fp_line
			(start -0.12065 0.3048)
			(end -0.67945 0.3048)
			(stroke
				(width 0.1)
				(type default)
			)
			(layer "F.Fab")
		)
		(fp_line
			(start 0.120396 0.3048)
			(end 0.120396 0.2794)
			(stroke
				(width 0.1)
				(type default)
			)
			(layer "F.Fab")
		)
		(fp_line
			(start 0.67945 0.3048)
			(end 0.120396 0.3048)
			(stroke
				(width 0.1)
				(type default)
			)
			(layer "F.Fab")
		)
		(fp_line
			(start -0.12065 0.2794)
			(end -0.12065 0.3048)
			(stroke
				(width 0.1)
				(type default)
			)
			(layer "F.Fab")
		)
		(fp_line
			(start 0.120396 0.2794)
			(end -0.12065 0.2794)
			(stroke
				(width 0.1)
				(type default)
			)
			(layer "F.Fab")
		)
		(fp_line
			(start -0.12065 -0.2794)
			(end 0.12065 -0.2794)
			(stroke
				(width 0.1)
				(type default)
			)
			(layer "F.Fab")
		)
		(fp_line
			(start 0.12065 -0.2794)
			(end 0.12065 -0.3048)
			(stroke
				(width 0.1)
				(type default)
			)
			(layer "F.Fab")
		)
		(fp_line
			(start 0.12065 -0.3048)
			(end 0.67945 -0.3048)
			(stroke
				(width 0.1)
				(type default)
			)
			(layer "F.Fab")
		)
		(fp_line
			(start 0.67945 -0.3048)
			(end 0.67945 0.3048)
			(stroke
				(width 0.1)
				(type default)
			)
			(layer "F.Fab")
		)
		(fp_line
			(start -0.67945 -0.305054)
			(end -0.12065 -0.305054)
			(stroke
				(width 0.1)
				(type default)
			)
			(layer "F.Fab")
		)
		(fp_line
			(start -0.12065 -0.305054)
			(end -0.12065 -0.2794)
			(stroke
				(width 0.1)
				(type default)
			)
			(layer "F.Fab")
		)
		(pad "1" smd circle
			(at -0.40005 0 270)
			(size 0 0)
			(layers "F.Cu" "F.Mask" "F.Paste")
			(net "LED_P12V_AUX_R2")
		)
		(pad "2" smd circle
			(at 0.40005 0 270)
			(size 0 0)
			(layers "F.Cu" "F.Mask" "F.Paste")
			(net "LED_P12V_AUX_R3")
		)
	)
	(footprint ""
		(layer "F.Cu")
		(at 155.98013 -70.26402 90)
		(property "Reference" "R2310"
			(at 0 0 90)
			(layer "F.SilkS")
			(hide yes)
			(effects
				(font
					(size 1.27 1.27)
				)
			)
		)
		(property "Value" ""
			(at 0 0 90)
			(layer "F.Fab")
			(effects
				(font
					(size 1.27 1.27)
				)
			)
		)
		(duplicate_pad_numbers_are_jumpers no)
		(fp_line
			(start 0.7874 -0.4064)
			(end 0.7874 0.4064)
			(stroke
				(width 0.1524)
				(type default)
			)
			(layer "F.SilkS")
		)
		(fp_line
			(start -0.7874 -0.4064)
			(end 0.7874 -0.4064)
			(stroke
				(width 0.1524)
				(type default)
			)
			(layer "F.SilkS")
		)
		(fp_line
			(start 0.7874 0.4064)
			(end -0.7874 0.4064)
			(stroke
				(width 0.1524)
				(type default)
			)
			(layer "F.SilkS")
		)
		(fp_line
			(start -0.7874 0.4064)
			(end -0.7874 -0.4064)
			(stroke
				(width 0.1524)
				(type default)
			)
			(layer "F.SilkS")
		)
		(fp_line
			(start -0.12065 -0.305054)
			(end -0.12065 -0.2794)
			(stroke
				(width 0.1)
				(type default)
			)
			(layer "F.Fab")
		)
		(fp_line
			(start -0.67945 -0.305054)
			(end -0.12065 -0.305054)
			(stroke
				(width 0.1)
				(type default)
			)
			(layer "F.Fab")
		)
		(fp_line
			(start 0.67945 -0.3048)
			(end 0.67945 0.3048)
			(stroke
				(width 0.1)
				(type default)
			)
			(layer "F.Fab")
		)
		(fp_line
			(start 0.12065 -0.3048)
			(end 0.67945 -0.3048)
			(stroke
				(width 0.1)
				(type default)
			)
			(layer "F.Fab")
		)
		(fp_line
			(start 0.12065 -0.2794)
			(end 0.12065 -0.3048)
			(stroke
				(width 0.1)
				(type default)
			)
			(layer "F.Fab")
		)
		(fp_line
			(start -0.12065 -0.2794)
			(end 0.12065 -0.2794)
			(stroke
				(width 0.1)
				(type default)
			)
			(layer "F.Fab")
		)
		(fp_line
			(start 0.120396 0.2794)
			(end -0.12065 0.2794)
			(stroke
				(width 0.1)
				(type default)
			)
			(layer "F.Fab")
		)
		(fp_line
			(start -0.12065 0.2794)
			(end -0.12065 0.3048)
			(stroke
				(width 0.1)
				(type default)
			)
			(layer "F.Fab")
		)
		(fp_line
			(start 0.67945 0.3048)
			(end 0.120396 0.3048)
			(stroke
				(width 0.1)
				(type default)
			)
			(layer "F.Fab")
		)
		(fp_line
			(start 0.120396 0.3048)
			(end 0.120396 0.2794)
			(stroke
				(width 0.1)
				(type default)
			)
			(layer "F.Fab")
		)
		(fp_line
			(start -0.12065 0.3048)
			(end -0.67945 0.3048)
			(stroke
				(width 0.1)
				(type default)
			)
			(layer "F.Fab")
		)
		(fp_line
			(start -0.67945 0.3048)
			(end -0.67945 -0.305054)
			(stroke
				(width 0.1)
				(type default)
			)
			(layer "F.Fab")
		)
		(pad "1" smd circle
			(at -0.40005 0 90)
			(size 0 0)
			(layers "F.Cu" "F.Mask" "F.Paste")
			(net "P3V3_AUX")
		)
		(pad "2" smd circle
			(at 0.40005 0 90)
			(size 0 0)
			(layers "F.Cu" "F.Mask" "F.Paste")
			(net "PCA9543_S3M_ADDR0")
		)
	)
)
